# S9S_MB_2U (Grand Teton) — schematic netlist excerpt (pin names and nets, part order shuffled) for the footprints in the layout excerpt that follows; sources: Cadence DE-HDL packaged netlist, KiCad conversion of 03242023_DA0F0TMBIJ0_F0T_Motherboard_J_brd_V01_OCP.brd

PJ62  Q_SHORT  EMPTY  pkg SM  page 262 : \1\ = SH_P1V05_PCH_AUX_P ; \2\ = P1V05_PCH_AUX
R153  Q_RES  100 1% CHIP  pkg 0402LF  page 125 : A = PWRGD_DRAMPWRGD_CPU1_GH_LVC1_R2 ; B = PVCCD_HV_CPU1
C30  Q_CAP  10UF 16V 10% X6S  pkg C0805  page 91 : A = P12V_S3_AUX_CPU0_NVDIMM ; B = GND

(kicad_pcb
	(version 20260206)
	(generator "pcbnew")
	(generator_version "10.0")
	(general
		(thickness 1.6)
		(legacy_teardrops no)
	)
	(paper "A4")
	(title_block
		(title "03242023_DA0F0TMBIJ0_F0T_Motherboard_J_brd_V01_OCP.brd")
		(comment 1 "Grand Teton / footprints 4803-4805 of 6105")
	)
	(layers
		(0 "F.Cu" signal "TOP")
		(4 "In1.Cu" signal "GND")
		(6 "In2.Cu" signal "IN1")
		(8 "In3.Cu" signal "GND1")
		(10 "In4.Cu" signal "IN2")
		(12 "In5.Cu" signal "GND2")
		(14 "In6.Cu" signal "IN3")
		(16 "In7.Cu" signal "GND3")
		(18 "In8.Cu" signal "VCC")
		(20 "In9.Cu" signal "VCC1")
		(22 "In10.Cu" signal "GND4")
		(24 "In11.Cu" signal "IN4")
		(26 "In12.Cu" signal "GND5")
		(28 "In13.Cu" signal "IN5")
		(30 "In14.Cu" signal "GND6")
		(32 "In15.Cu" signal "IN6")
		(34 "In16.Cu" signal "GND7")
		(2 "B.Cu" signal "BOTTOM")
		(9 "F.Adhes" user "F.Adhesive")
		(11 "B.Adhes" user "B.Adhesive")
		(13 "F.Paste" user "Package Geometry/Pastemask Top")
		(15 "B.Paste" user "Package Geometry/Pastemask Bottom")
		(5 "F.SilkS" user "Ref Des/Silkscreen Top")
		(7 "B.SilkS" user "Ref Des/Silkscreen Bottom")
		(1 "F.Mask" user "Board Geometry/Soldermask Top")
		(3 "B.Mask" user "Board Geometry/Soldermask Bottom")
		(17 "Dwgs.User" user "User.Drawings")
		(19 "Cmts.User" user "User.Comments")
		(21 "Eco1.User" user "User.Eco1")
		(23 "Eco2.User" user "User.Eco2")
		(25 "Edge.Cuts" user "Board Geometry/Outline")
		(27 "Margin" user)
		(31 "F.CrtYd" user "Package Geometry/Place Bound Top")
		(29 "B.CrtYd" user "Package Geometry/Place Bound Bottom")
		(35 "F.Fab" user "Ref Des/Assembly Top")
		(33 "B.Fab" user "Ref Des/Assembly Bottom")
	)
	(footprint ""
		(layer "B.Cu")
		(at 170.824398 -193.02603 90)
		(property "Reference" "R153"
			(at 0 0 90)
			(layer "B.SilkS")
			(hide yes)
			(effects
				(font
					(size 1.27 1.27)
				)
				(justify mirror)
			)
		)
		(property "Value" ""
			(at 0 0 90)
			(layer "B.Fab")
			(effects
				(font
					(size 1.27 1.27)
				)
				(justify mirror)
			)
		)
		(duplicate_pad_numbers_are_jumpers no)
		(fp_line
			(start 0.7874 -0.4064)
			(end -0.7874 -0.4064)
			(stroke
				(width 0.1524)
				(type default)
			)
			(layer "B.SilkS")
		)
		(fp_line
			(start -0.7874 -0.4064)
			(end -0.7874 0.4064)
			(stroke
				(width 0.1524)
				(type default)
			)
			(layer "B.SilkS")
		)
		(fp_line
			(start 0.7874 0.4064)
			(end 0.7874 -0.4064)
			(stroke
				(width 0.1524)
				(type default)
			)
			(layer "B.SilkS")
		)
		(fp_line
			(start -0.7874 0.4064)
			(end 0.7874 0.4064)
			(stroke
				(width 0.1524)
				(type default)
			)
			(layer "B.SilkS")
		)
		(fp_line
			(start 0.67945 -0.305054)
			(end 0.12065 -0.305054)
			(stroke
				(width 0.1)
				(type default)
			)
			(layer "B.Fab")
		)
		(fp_line
			(start 0.12065 -0.305054)
			(end 0.12065 -0.2794)
			(stroke
				(width 0.1)
				(type default)
			)
			(layer "B.Fab")
		)
		(fp_line
			(start -0.12065 -0.3048)
			(end -0.67945 -0.3048)
			(stroke
				(width 0.1)
				(type default)
			)
			(layer "B.Fab")
		)
		(fp_line
			(start -0.67945 -0.3048)
			(end -0.67945 0.3048)
			(stroke
				(width 0.1)
				(type default)
			)
			(layer "B.Fab")
		)
		(fp_line
			(start 0.12065 -0.2794)
			(end -0.12065 -0.2794)
			(stroke
				(width 0.1)
				(type default)
			)
			(layer "B.Fab")
		)
		(fp_line
			(start -0.12065 -0.2794)
			(end -0.12065 -0.3048)
			(stroke
				(width 0.1)
				(type default)
			)
			(layer "B.Fab")
		)
		(fp_line
			(start 0.12065 0.2794)
			(end 0.12065 0.3048)
			(stroke
				(width 0.1)
				(type default)
			)
			(layer "B.Fab")
		)
		(fp_line
			(start -0.120396 0.2794)
			(end 0.12065 0.2794)
			(stroke
				(width 0.1)
				(type default)
			)
			(layer "B.Fab")
		)
		(fp_line
			(start 0.67945 0.3048)
			(end 0.67945 -0.305054)
			(stroke
				(width 0.1)
				(type default)
			)
			(layer "B.Fab")
		)
		(fp_line
			(start 0.12065 0.3048)
			(end 0.67945 0.3048)
			(stroke
				(width 0.1)
				(type default)
			)
			(layer "B.Fab")
		)
		(fp_line
			(start -0.120396 0.3048)
			(end -0.120396 0.2794)
			(stroke
				(width 0.1)
				(type default)
			)
			(layer "B.Fab")
		)
		(fp_line
			(start -0.67945 0.3048)
			(end -0.120396 0.3048)
			(stroke
				(width 0.1)
				(type default)
			)
			(layer "B.Fab")
		)
		(pad "1" smd circle
			(at 0.40005 0 270)
			(size 0 0)
			(layers "B.Cu" "B.Mask" "B.Paste")
			(net "PWRGD_DRAMPWRGD_CPU1_GH_LVC1_R2")
		)
		(pad "2" smd circle
			(at -0.40005 0 270)
			(size 0 0)
			(layers "B.Cu" "B.Mask" "B.Paste")
			(net "PVCCD_HV_CPU1")
		)
	)
	(footprint ""
		(layer "B.Cu")
		(at 325.688706 -73.499472 180)
		(property "Reference" "PJ62"
			(at -4.991354 -1.577594 0)
			(unlocked yes)
			(layer "B.SilkS")
			(effects
				(font
					(size 0.7874 0.5842)
					(thickness 0.1524)
				)
				(justify left mirror)
			)
		)
		(property "Value" ""
			(at 0 0 0)
			(layer "B.Fab")
			(effects
				(font
					(size 1.27 1.27)
				)
				(justify mirror)
			)
		)
		(duplicate_pad_numbers_are_jumpers no)
		(pad "1" smd circle
			(at 0.7493 0 270)
			(size 0 0)
			(layers "B.Cu" "B.Mask" "B.Paste")
			(net "SH_P1V05_PCH_AUX_P")
		)
		(pad "2" smd rect
			(at -0.7493 0 90)
			(size 0.7112 0.8128)
			(layers "B.Cu" "B.Mask" "B.Paste")
			(net "P1V05_PCH_AUX")
		)
		(zone
			(layer "B.Cu")
			(hatch none 0.5)
			(connect_pads
				(clearance 0)
			)
			(min_thickness 0.25)
			(keepout
				(tracks allowed)
				(vias not_allowed)
				(pads allowed)
				(copperpour not_allowed)
				(footprints allowed)
			)
			(placement
				(enabled no)
				(sheetname "")
			)
			(fill
				(thermal_gap 0.5)
				(thermal_bridge_width 0.5)
				(island_removal_mode 0)
			)
			(polygon
				(pts
					(xy 324.507606 -73.910952) (xy 324.507606 -73.093326) (xy 326.895206 -73.093326) (xy 326.895206 -73.910952)
				)
			)
		)
	)
	(footprint ""
		(layer "B.Cu")
		(at 410.830014 -321.549776 -90)
		(property "Reference" "C30"
			(at 0 0 90)
			(layer "B.SilkS")
			(hide yes)
			(effects
				(font
					(size 1.27 1.27)
				)
				(justify mirror)
			)
		)
		(property "Value" ""
			(at 0 0 90)
			(layer "B.Fab")
			(effects
				(font
					(size 1.27 1.27)
				)
				(justify mirror)
			)
		)
		(duplicate_pad_numbers_are_jumpers no)
		(fp_line
			(start -1.524 0.762)
			(end 1.524 0.762)
			(stroke
				(width 0.1524)
				(type default)
			)
			(layer "B.SilkS")
		)
		(fp_line
			(start 1.524 0.762)
			(end 1.524 -0.762)
			(stroke
				(width 0.1524)
				(type default)
			)
			(layer "B.SilkS")
		)
		(fp_line
			(start -1.524 -0.762)
			(end -1.524 0.762)
			(stroke
				(width 0.1524)
				(type default)
			)
			(layer "B.SilkS")
		)
		(fp_line
			(start 1.524 -0.762)
			(end -1.524 -0.762)
			(stroke
				(width 0.1524)
				(type default)
			)
			(layer "B.SilkS")
		)
		(fp_line
			(start -1.1049 0.724916)
			(end -1.1049 -0.724916)
			(stroke
				(width 0.1)
				(type default)
			)
			(layer "B.Fab")
		)
		(fp_line
			(start 1.1049 0.724916)
			(end -1.1049 0.724916)
			(stroke
				(width 0.1)
				(type default)
			)
			(layer "B.Fab")
		)
		(fp_line
			(start -1.1049 -0.724916)
			(end 1.1049 -0.724916)
			(stroke
				(width 0.1)
				(type default)
			)
			(layer "B.Fab")
		)
		(fp_line
			(start 1.1049 -0.724916)
			(end 1.1049 0.724916)
			(stroke
				(width 0.1)
				(type default)
			)
			(layer "B.Fab")
		)
		(pad "1" smd rect
			(at 0.889 0 270)
			(size 1.016 1.27)
			(layers "B.Cu" "B.Mask" "B.Paste")
			(net "P12V_S3_AUX_CPU0_NVDIMM")
		)
		(pad "2" smd rect
			(at -0.889 0 270)
			(size 1.016 1.27)
			(layers "B.Cu" "B.Mask" "B.Paste")
			(net "GND")
		)
	)
)
